(kicad_pcb
	(version 20260206)
	(generator "pcbnew")
	(generator_version "10.0")
	(general
		(thickness 1.6)
		(legacy_teardrops no)
	)
	(paper "A4")
	(title_block
		(title "panther-plus-userver — 13130-1b_20150205.brd")
		(comment 1 "Honey Badger (Wiwynn) / footprint 894 of 1509 (DIMM1), pads 177-183 of 210")
	)
	(layers
		(0 "F.Cu" signal "TOP")
		(4 "In1.Cu" signal "L2")
		(6 "In2.Cu" signal "L3")
		(8 "In3.Cu" signal "L4")
		(10 "In4.Cu" signal "L5")
		(12 "In5.Cu" signal "L6")
		(14 "In6.Cu" signal "L7")
		(16 "In7.Cu" signal "L8")
		(18 "In8.Cu" signal "L9")
		(20 "In9.Cu" signal "L10")
		(22 "In10.Cu" signal "L11")
		(2 "B.Cu" signal "BOTTOM")
		(9 "F.Adhes" user "F.Adhesive")
		(11 "B.Adhes" user "B.Adhesive")
		(13 "F.Paste" user "Package Geometry/Pastemask Top")
		(15 "B.Paste" user "Package Geometry/Pastemask Bottom")
		(5 "F.SilkS" user "Ref Des/Silkscreen Top")
		(7 "B.SilkS" user "Ref Des/Silkscreen Bottom")
		(1 "F.Mask" user "Board Geometry/Soldermask Top")
		(3 "B.Mask" user "Board Geometry/Soldermask Bottom")
		(17 "Dwgs.User" user "User.Drawings")
		(19 "Cmts.User" user "User.Comments")
		(21 "Eco1.User" user "User.Eco1")
		(23 "Eco2.User" user "User.Eco2")
		(25 "Edge.Cuts" user "Board Geometry/Outline")
		(27 "Margin" user)
		(31 "F.CrtYd" user "Package Geometry/Place Bound Top")
		(29 "B.CrtYd" user "Package Geometry/Place Bound Bottom")
		(35 "F.Fab" user "Ref Des/Assembly Top")
		(33 "B.Fab" user "Ref Des/Assembly Bottom")
	)
	(footprint ""
		(layer "B.Cu")
		(at 158.500064 -66.699892 180)
		(property "Reference" "DIMM1"
			(at 0 0 0)
			(layer "B.SilkS")
			(hide yes)
			(effects
				(font
					(size 1.27 1.27)
				)
				(justify mirror)
			)
		)
		(property "Value" "DDR3-204P-142-COLAY-1-GP-U"
			(at 41.312338 -16.676878 180)
			(unlocked yes)
			(layer "B.Fab")
			(hide yes)
			(effects
				(font
					(size 1.016 1.016)
					(thickness 0.1524)
				)
				(justify mirror)
			)
		)
		(property "Device Type" "AS0A626-J8R6-7H-COLAY-1"
			(at 41.312338 -18.200878 180)
			(unlocked yes)
			(layer "B.Fab")
			(hide yes)
			(effects
				(font
					(size 1.016 1.016)
					(thickness 0.1524)
				)
				(justify mirror)
			)
		)
		(duplicate_pad_numbers_are_jumpers no)
		(pad "175" smd custom
			(at 22.949916 -4.100068)
			(size 0.1143 0.1143)
			(layers "B.Cu" "B.Mask" "B.Paste")
			(net "GND")
			(options
				(clearance outline)
				(anchor circle)
			)
			(primitives
				(gr_poly
					(pts
						(xy 0 -0.9017) (xy -0.03175 -0.89916) (xy -0.0635 -0.889) (xy -0.09144 -0.87376) (xy -0.11684 -0.85344)
						(xy -0.13716 -0.82804) (xy -0.1524 -0.8001) (xy -0.16256 -0.76835) (xy -0.1651 -0.7366) (xy -0.1651 -0.19685)
						(xy -0.17272 -0.18923) (xy -0.17907 -0.18034) (xy -0.18669 -0.17145) (xy -0.19177 -0.16256) (xy -0.19812 -0.15367)
						(xy -0.20828 -0.13335) (xy -0.21971 -0.10287) (xy -0.22225 -0.09271) (xy -0.22479 -0.08128) (xy -0.22606 -0.07112)
						(xy -0.2286 -0.05969) (xy -0.2286 -0.01651) (xy -0.22606 -0.00508) (xy -0.22479 0.00508) (xy -0.22225 0.01651)
						(xy -0.21971 0.02667) (xy -0.20828 0.05715) (xy -0.19812 0.07747) (xy -0.19177 0.08636) (xy -0.18669 0.09525)
						(xy -0.17907 0.10414) (xy -0.17272 0.11303) (xy -0.1651 0.12065) (xy -0.1651 0.7366) (xy -0.16256 0.76835)
						(xy -0.1524 0.8001) (xy -0.13716 0.82804) (xy -0.11684 0.85344) (xy -0.09144 0.87376) (xy -0.0635 0.889)
						(xy -0.03175 0.89916) (xy 0 0.9017) (xy 0.03175 0.89916) (xy 0.0635 0.889) (xy 0.09144 0.87376)
						(xy 0.11684 0.85344) (xy 0.13716 0.82804) (xy 0.1524 0.8001) (xy 0.16256 0.76835) (xy 0.1651 0.7366)
						(xy 0.1651 0.11938) (xy 0.17272 0.11176) (xy 0.19812 0.0762) (xy 0.2032 0.06604) (xy 0.20701 0.05715)
						(xy 0.21209 0.04699) (xy 0.2159 0.03683) (xy 0.21844 0.02667) (xy 0.22225 0.01524) (xy 0.22352 0.00508)
						(xy 0.22606 -0.00508) (xy 0.22733 -0.01651) (xy 0.22733 -0.02667) (xy 0.2286 -0.0381) (xy 0.22733 -0.04953)
						(xy 0.22733 -0.05969) (xy 0.22606 -0.07112) (xy 0.22352 -0.08128) (xy 0.22225 -0.09144) (xy 0.21844 -0.10287)
						(xy 0.2159 -0.11303) (xy 0.21209 -0.12319) (xy 0.20701 -0.13335) (xy 0.2032 -0.14224) (xy 0.19812 -0.1524)
						(xy 0.17272 -0.18796) (xy 0.1651 -0.19558) (xy 0.1651 -0.7366) (xy 0.16256 -0.76835) (xy 0.1524 -0.8001)
						(xy 0.13716 -0.82804) (xy 0.11684 -0.85344) (xy 0.09144 -0.87376) (xy 0.0635 -0.889) (xy 0.03175 -0.89916)
					)
					(width 0)
					(fill yes)
				)
			)
		)
		(pad "176" smd custom
			(at 23.24989 4.100068)
			(size 0.1143 0.1143)
			(layers "B.Cu" "B.Mask" "B.Paste")
			(net "M_A_DQ55")
			(options
				(clearance outline)
				(anchor circle)
			)
			(primitives
				(gr_poly
					(pts
						(xy 0 -0.9017) (xy -0.03175 -0.89916) (xy -0.0635 -0.889) (xy -0.09144 -0.87376) (xy -0.11684 -0.85344)
						(xy -0.13716 -0.82804) (xy -0.1524 -0.8001) (xy -0.16256 -0.76835) (xy -0.1651 -0.7366) (xy -0.1651 -0.11938)
						(xy -0.17272 -0.11176) (xy -0.19812 -0.0762) (xy -0.2032 -0.06604) (xy -0.20701 -0.05715) (xy -0.21209 -0.04699)
						(xy -0.2159 -0.03683) (xy -0.21844 -0.02667) (xy -0.22225 -0.01524) (xy -0.22352 -0.00508) (xy -0.22606 0.00508)
						(xy -0.22733 0.01651) (xy -0.22733 0.02667) (xy -0.2286 0.0381) (xy -0.22733 0.04953) (xy -0.22733 0.05969)
						(xy -0.22606 0.07112) (xy -0.22352 0.08128) (xy -0.22225 0.09144) (xy -0.21844 0.10287) (xy -0.2159 0.11303)
						(xy -0.21209 0.12319) (xy -0.20701 0.13335) (xy -0.2032 0.14224) (xy -0.19812 0.1524) (xy -0.17272 0.18796)
						(xy -0.1651 0.19558) (xy -0.1651 0.7366) (xy -0.16256 0.76835) (xy -0.1524 0.8001) (xy -0.13716 0.82804)
						(xy -0.11684 0.85344) (xy -0.09144 0.87376) (xy -0.0635 0.889) (xy -0.03175 0.89916) (xy 0 0.9017)
						(xy 0.03175 0.89916) (xy 0.0635 0.889) (xy 0.09144 0.87376) (xy 0.11684 0.85344) (xy 0.13716 0.82804)
						(xy 0.1524 0.8001) (xy 0.16256 0.76835) (xy 0.1651 0.7366) (xy 0.1651 0.19685) (xy 0.17272 0.18923)
						(xy 0.17907 0.18034) (xy 0.18669 0.17145) (xy 0.19177 0.16256) (xy 0.19812 0.15367) (xy 0.20828 0.13335)
						(xy 0.21971 0.10287) (xy 0.22225 0.09271) (xy 0.22479 0.08128) (xy 0.22606 0.07112) (xy 0.2286 0.05969)
						(xy 0.2286 0.01651) (xy 0.22606 0.00508) (xy 0.22479 -0.00508) (xy 0.22225 -0.01651) (xy 0.21971 -0.02667)
						(xy 0.20828 -0.05715) (xy 0.19812 -0.07747) (xy 0.19177 -0.08636) (xy 0.18669 -0.09525) (xy 0.17907 -0.10414)
						(xy 0.17272 -0.11303) (xy 0.1651 -0.12065) (xy 0.1651 -0.7366) (xy 0.16256 -0.76835) (xy 0.1524 -0.8001)
						(xy 0.13716 -0.82804) (xy 0.11684 -0.85344) (xy 0.09144 -0.87376) (xy 0.0635 -0.889) (xy 0.03175 -0.89916)
					)
					(width 0)
					(fill yes)
				)
			)
		)
		(pad "177" smd custom
			(at 23.550118 -4.100068)
			(size 0.1143 0.1143)
			(layers "B.Cu" "B.Mask" "B.Paste")
			(net "M_A_DQ50")
			(options
				(clearance outline)
				(anchor circle)
			)
			(primitives
				(gr_poly
					(pts
						(xy 0 -0.9017) (xy -0.03175 -0.89916) (xy -0.0635 -0.889) (xy -0.09144 -0.87376) (xy -0.11684 -0.85344)
						(xy -0.13716 -0.82804) (xy -0.1524 -0.8001) (xy -0.16256 -0.76835) (xy -0.1651 -0.7366) (xy -0.1651 -0.44958)
						(xy -0.17272 -0.44196) (xy -0.19812 -0.4064) (xy -0.2032 -0.39624) (xy -0.20701 -0.38735) (xy -0.21209 -0.37719)
						(xy -0.2159 -0.36703) (xy -0.21844 -0.35687) (xy -0.22225 -0.34544) (xy -0.22352 -0.33528) (xy -0.22606 -0.32512)
						(xy -0.22733 -0.31369) (xy -0.22733 -0.30353) (xy -0.2286 -0.2921) (xy -0.22733 -0.28067) (xy -0.22733 -0.27051)
						(xy -0.22606 -0.25908) (xy -0.22352 -0.24892) (xy -0.22225 -0.23876) (xy -0.21844 -0.22733) (xy -0.2159 -0.21717)
						(xy -0.21209 -0.20701) (xy -0.20701 -0.19685) (xy -0.2032 -0.18796) (xy -0.19812 -0.1778) (xy -0.17272 -0.14224)
						(xy -0.1651 -0.13462) (xy -0.1651 0.7366) (xy -0.16256 0.76835) (xy -0.1524 0.8001) (xy -0.13716 0.82804)
						(xy -0.11684 0.85344) (xy -0.09144 0.87376) (xy -0.0635 0.889) (xy -0.03175 0.89916) (xy 0 0.9017)
						(xy 0.03175 0.89916) (xy 0.0635 0.889) (xy 0.09144 0.87376) (xy 0.11684 0.85344) (xy 0.13716 0.82804)
						(xy 0.1524 0.8001) (xy 0.16256 0.76835) (xy 0.1651 0.7366) (xy 0.1651 -0.13462) (xy 0.17272 -0.14224)
						(xy 0.19812 -0.1778) (xy 0.2032 -0.18796) (xy 0.20701 -0.19685) (xy 0.21209 -0.20701) (xy 0.2159 -0.21717)
						(xy 0.21844 -0.22733) (xy 0.22225 -0.23876) (xy 0.22352 -0.24892) (xy 0.22606 -0.25908) (xy 0.22733 -0.27051)
						(xy 0.22733 -0.28067) (xy 0.2286 -0.2921) (xy 0.22733 -0.30353) (xy 0.22733 -0.31369) (xy 0.22606 -0.32512)
						(xy 0.22352 -0.33528) (xy 0.22225 -0.34544) (xy 0.21844 -0.35687) (xy 0.2159 -0.36703) (xy 0.21209 -0.37719)
						(xy 0.20701 -0.38735) (xy 0.2032 -0.39624) (xy 0.19812 -0.4064) (xy 0.17272 -0.44196) (xy 0.1651 -0.44958)
						(xy 0.1651 -0.7366) (xy 0.16256 -0.76835) (xy 0.1524 -0.8001) (xy 0.13716 -0.82804) (xy 0.11684 -0.85344)
						(xy 0.09144 -0.87376) (xy 0.0635 -0.889) (xy 0.03175 -0.89916)
					)
					(width 0)
					(fill yes)
				)
			)
		)
		(pad "178" smd custom
			(at 23.850092 4.100068)
			(size 0.1143 0.1143)
			(layers "B.Cu" "B.Mask" "B.Paste")
			(net "GND")
			(options
				(clearance outline)
				(anchor circle)
			)
			(primitives
				(gr_poly
					(pts
						(xy 0 -0.9017) (xy -0.03175 -0.89916) (xy -0.0635 -0.889) (xy -0.09144 -0.87376) (xy -0.11684 -0.85344)
						(xy -0.13716 -0.82804) (xy -0.1524 -0.8001) (xy -0.16256 -0.76835) (xy -0.1651 -0.7366) (xy -0.1651 0.13462)
						(xy -0.17272 0.14224) (xy -0.19812 0.1778) (xy -0.2032 0.18796) (xy -0.20701 0.19685) (xy -0.21209 0.20701)
						(xy -0.2159 0.21717) (xy -0.21844 0.22733) (xy -0.22225 0.23876) (xy -0.22352 0.24892) (xy -0.22606 0.25908)
						(xy -0.22733 0.27051) (xy -0.22733 0.28067) (xy -0.2286 0.2921) (xy -0.22733 0.30353) (xy -0.22733 0.31369)
						(xy -0.22606 0.32512) (xy -0.22352 0.33528) (xy -0.22225 0.34544) (xy -0.21844 0.35687) (xy -0.2159 0.36703)
						(xy -0.21209 0.37719) (xy -0.20701 0.38735) (xy -0.2032 0.39624) (xy -0.19812 0.4064) (xy -0.17272 0.44196)
						(xy -0.1651 0.44958) (xy -0.1651 0.7366) (xy -0.16256 0.76835) (xy -0.1524 0.8001) (xy -0.13716 0.82804)
						(xy -0.11684 0.85344) (xy -0.09144 0.87376) (xy -0.0635 0.889) (xy -0.03175 0.89916) (xy 0 0.9017)
						(xy 0.03175 0.89916) (xy 0.0635 0.889) (xy 0.09144 0.87376) (xy 0.11684 0.85344) (xy 0.13716 0.82804)
						(xy 0.1524 0.8001) (xy 0.16256 0.76835) (xy 0.1651 0.7366) (xy 0.1651 0.44958) (xy 0.17272 0.44196)
						(xy 0.19812 0.4064) (xy 0.2032 0.39624) (xy 0.20701 0.38735) (xy 0.21209 0.37719) (xy 0.2159 0.36703)
						(xy 0.21844 0.35687) (xy 0.22225 0.34544) (xy 0.22352 0.33528) (xy 0.22606 0.32512) (xy 0.22733 0.31369)
						(xy 0.22733 0.30353) (xy 0.2286 0.2921) (xy 0.22733 0.28067) (xy 0.22733 0.27051) (xy 0.22606 0.25908)
						(xy 0.22352 0.24892) (xy 0.22225 0.23876) (xy 0.21844 0.22733) (xy 0.2159 0.21717) (xy 0.21209 0.20701)
						(xy 0.20701 0.19685) (xy 0.2032 0.18796) (xy 0.19812 0.1778) (xy 0.17272 0.14224) (xy 0.1651 0.13462)
						(xy 0.1651 -0.7366) (xy 0.16256 -0.76835) (xy 0.1524 -0.8001) (xy 0.13716 -0.82804) (xy 0.11684 -0.85344)
						(xy 0.09144 -0.87376) (xy 0.0635 -0.889) (xy 0.03175 -0.89916)
					)
					(width 0)
					(fill yes)
				)
			)
		)
		(pad "179" smd custom
			(at 24.150066 -4.100068)
			(size 0.1143 0.1143)
			(layers "B.Cu" "B.Mask" "B.Paste")
			(net "M_A_DQ51")
			(options
				(clearance outline)
				(anchor circle)
			)
			(primitives
				(gr_poly
					(pts
						(xy 0 -0.9017) (xy -0.03175 -0.89916) (xy -0.0635 -0.889) (xy -0.09144 -0.87376) (xy -0.11684 -0.85344)
						(xy -0.13716 -0.82804) (xy -0.1524 -0.8001) (xy -0.16256 -0.76835) (xy -0.1651 -0.7366) (xy -0.1651 -0.19685)
						(xy -0.17272 -0.18923) (xy -0.17907 -0.18034) (xy -0.18669 -0.17145) (xy -0.19177 -0.16256) (xy -0.19812 -0.15367)
						(xy -0.20828 -0.13335) (xy -0.21971 -0.10287) (xy -0.22225 -0.09271) (xy -0.22479 -0.08128) (xy -0.22606 -0.07112)
						(xy -0.2286 -0.05969) (xy -0.2286 -0.01651) (xy -0.22606 -0.00508) (xy -0.22479 0.00508) (xy -0.22225 0.01651)
						(xy -0.21971 0.02667) (xy -0.20828 0.05715) (xy -0.19812 0.07747) (xy -0.19177 0.08636) (xy -0.18669 0.09525)
						(xy -0.17907 0.10414) (xy -0.17272 0.11303) (xy -0.1651 0.12065) (xy -0.1651 0.7366) (xy -0.16256 0.76835)
						(xy -0.1524 0.8001) (xy -0.13716 0.82804) (xy -0.11684 0.85344) (xy -0.09144 0.87376) (xy -0.0635 0.889)
						(xy -0.03175 0.89916) (xy 0 0.9017) (xy 0.03175 0.89916) (xy 0.0635 0.889) (xy 0.09144 0.87376)
						(xy 0.11684 0.85344) (xy 0.13716 0.82804) (xy 0.1524 0.8001) (xy 0.16256 0.76835) (xy 0.1651 0.7366)
						(xy 0.1651 0.11938) (xy 0.17272 0.11176) (xy 0.19812 0.0762) (xy 0.2032 0.06604) (xy 0.20701 0.05715)
						(xy 0.21209 0.04699) (xy 0.2159 0.03683) (xy 0.21844 0.02667) (xy 0.22225 0.01524) (xy 0.22352 0.00508)
						(xy 0.22606 -0.00508) (xy 0.22733 -0.01651) (xy 0.22733 -0.02667) (xy 0.2286 -0.0381) (xy 0.22733 -0.04953)
						(xy 0.22733 -0.05969) (xy 0.22606 -0.07112) (xy 0.22352 -0.08128) (xy 0.22225 -0.09144) (xy 0.21844 -0.10287)
						(xy 0.2159 -0.11303) (xy 0.21209 -0.12319) (xy 0.20701 -0.13335) (xy 0.2032 -0.14224) (xy 0.19812 -0.1524)
						(xy 0.17272 -0.18796) (xy 0.1651 -0.19558) (xy 0.1651 -0.7366) (xy 0.16256 -0.76835) (xy 0.1524 -0.8001)
						(xy 0.13716 -0.82804) (xy 0.11684 -0.85344) (xy 0.09144 -0.87376) (xy 0.0635 -0.889) (xy 0.03175 -0.89916)
					)
					(width 0)
					(fill yes)
				)
			)
		)
		(pad "180" smd custom
			(at 24.45004 4.100068)
			(size 0.1143 0.1143)
			(layers "B.Cu" "B.Mask" "B.Paste")
			(net "M_A_DQ60")
			(options
				(clearance outline)
				(anchor circle)
			)
			(primitives
				(gr_poly
					(pts
						(xy 0 -0.9017) (xy -0.03175 -0.89916) (xy -0.0635 -0.889) (xy -0.09144 -0.87376) (xy -0.11684 -0.85344)
						(xy -0.13716 -0.82804) (xy -0.1524 -0.8001) (xy -0.16256 -0.76835) (xy -0.1651 -0.7366) (xy -0.1651 -0.11938)
						(xy -0.17272 -0.11176) (xy -0.19812 -0.0762) (xy -0.2032 -0.06604) (xy -0.20701 -0.05715) (xy -0.21209 -0.04699)
						(xy -0.2159 -0.03683) (xy -0.21844 -0.02667) (xy -0.22225 -0.01524) (xy -0.22352 -0.00508) (xy -0.22606 0.00508)
						(xy -0.22733 0.01651) (xy -0.22733 0.02667) (xy -0.2286 0.0381) (xy -0.22733 0.04953) (xy -0.22733 0.05969)
						(xy -0.22606 0.07112) (xy -0.22352 0.08128) (xy -0.22225 0.09144) (xy -0.21844 0.10287) (xy -0.2159 0.11303)
						(xy -0.21209 0.12319) (xy -0.20701 0.13335) (xy -0.2032 0.14224) (xy -0.19812 0.1524) (xy -0.17272 0.18796)
						(xy -0.1651 0.19558) (xy -0.1651 0.7366) (xy -0.16256 0.76835) (xy -0.1524 0.8001) (xy -0.13716 0.82804)
						(xy -0.11684 0.85344) (xy -0.09144 0.87376) (xy -0.0635 0.889) (xy -0.03175 0.89916) (xy 0 0.9017)
						(xy 0.03175 0.89916) (xy 0.0635 0.889) (xy 0.09144 0.87376) (xy 0.11684 0.85344) (xy 0.13716 0.82804)
						(xy 0.1524 0.8001) (xy 0.16256 0.76835) (xy 0.1651 0.7366) (xy 0.1651 0.19685) (xy 0.17272 0.18923)
						(xy 0.17907 0.18034) (xy 0.18669 0.17145) (xy 0.19177 0.16256) (xy 0.19812 0.15367) (xy 0.20828 0.13335)
						(xy 0.21971 0.10287) (xy 0.22225 0.09271) (xy 0.22479 0.08128) (xy 0.22606 0.07112) (xy 0.2286 0.05969)
						(xy 0.2286 0.01651) (xy 0.22606 0.00508) (xy 0.22479 -0.00508) (xy 0.22225 -0.01651) (xy 0.21971 -0.02667)
						(xy 0.20828 -0.05715) (xy 0.19812 -0.07747) (xy 0.19177 -0.08636) (xy 0.18669 -0.09525) (xy 0.17907 -0.10414)
						(xy 0.17272 -0.11303) (xy 0.1651 -0.12065) (xy 0.1651 -0.7366) (xy 0.16256 -0.76835) (xy 0.1524 -0.8001)
						(xy 0.13716 -0.82804) (xy 0.11684 -0.85344) (xy 0.09144 -0.87376) (xy 0.0635 -0.889) (xy 0.03175 -0.89916)
					)
					(width 0)
					(fill yes)
				)
			)
		)
		(pad "181" smd custom
			(at 24.750014 -4.100068)
			(size 0.1143 0.1143)
			(layers "B.Cu" "B.Mask" "B.Paste")
			(net "GND")
			(options
				(clearance outline)
				(anchor circle)
			)
			(primitives
				(gr_poly
					(pts
						(xy 0 -0.9017) (xy -0.03175 -0.89916) (xy -0.0635 -0.889) (xy -0.09144 -0.87376) (xy -0.11684 -0.85344)
						(xy -0.13716 -0.82804) (xy -0.1524 -0.8001) (xy -0.16256 -0.76835) (xy -0.1651 -0.7366) (xy -0.1651 -0.44958)
						(xy -0.17272 -0.44196) (xy -0.19812 -0.4064) (xy -0.2032 -0.39624) (xy -0.20701 -0.38735) (xy -0.21209 -0.37719)
						(xy -0.2159 -0.36703) (xy -0.21844 -0.35687) (xy -0.22225 -0.34544) (xy -0.22352 -0.33528) (xy -0.22606 -0.32512)
						(xy -0.22733 -0.31369) (xy -0.22733 -0.30353) (xy -0.2286 -0.2921) (xy -0.22733 -0.28067) (xy -0.22733 -0.27051)
						(xy -0.22606 -0.25908) (xy -0.22352 -0.24892) (xy -0.22225 -0.23876) (xy -0.21844 -0.22733) (xy -0.2159 -0.21717)
						(xy -0.21209 -0.20701) (xy -0.20701 -0.19685) (xy -0.2032 -0.18796) (xy -0.19812 -0.1778) (xy -0.17272 -0.14224)
						(xy -0.1651 -0.13462) (xy -0.1651 0.7366) (xy -0.16256 0.76835) (xy -0.1524 0.8001) (xy -0.13716 0.82804)
						(xy -0.11684 0.85344) (xy -0.09144 0.87376) (xy -0.0635 0.889) (xy -0.03175 0.89916) (xy 0 0.9017)
						(xy 0.03175 0.89916) (xy 0.0635 0.889) (xy 0.09144 0.87376) (xy 0.11684 0.85344) (xy 0.13716 0.82804)
						(xy 0.1524 0.8001) (xy 0.16256 0.76835) (xy 0.1651 0.7366) (xy 0.1651 -0.13462) (xy 0.17272 -0.14224)
						(xy 0.19812 -0.1778) (xy 0.2032 -0.18796) (xy 0.20701 -0.19685) (xy 0.21209 -0.20701) (xy 0.2159 -0.21717)
						(xy 0.21844 -0.22733) (xy 0.22225 -0.23876) (xy 0.22352 -0.24892) (xy 0.22606 -0.25908) (xy 0.22733 -0.27051)
						(xy 0.22733 -0.28067) (xy 0.2286 -0.2921) (xy 0.22733 -0.30353) (xy 0.22733 -0.31369) (xy 0.22606 -0.32512)
						(xy 0.22352 -0.33528) (xy 0.22225 -0.34544) (xy 0.21844 -0.35687) (xy 0.2159 -0.36703) (xy 0.21209 -0.37719)
						(xy 0.20701 -0.38735) (xy 0.2032 -0.39624) (xy 0.19812 -0.4064) (xy 0.17272 -0.44196) (xy 0.1651 -0.44958)
						(xy 0.1651 -0.7366) (xy 0.16256 -0.76835) (xy 0.1524 -0.8001) (xy 0.13716 -0.82804) (xy 0.11684 -0.85344)
						(xy 0.09144 -0.87376) (xy 0.0635 -0.889) (xy 0.03175 -0.89916)
					)
					(width 0)
					(fill yes)
				)
			)
		)
	)
)
